FILE_TYPE = CONNECTIVITY;
{Allegro Design Entry HDL 17.2-2016 S081 (4005846) 1/11/2022}
"PAGE_NUMBER" = 126;
0"NC";
END.
